(kicad_pcb
	(version 20241229)
	(generator "pcbnew")
	(generator_version "9.0")
	(general
		(thickness 1.294)
		(legacy_teardrops no)
	)
	(paper "A3")
	(title_block
		(title "Kintex 410T devboard")
		(date "2024-04-03")
		(rev "1.1.2")
		(comment 9 "footprints 573-578 of 975")
	)
	(layers
		(0 "F.Cu" mixed)
		(4 "In1.Cu" power)
		(6 "In2.Cu" power)
		(8 "In3.Cu" mixed)
		(10 "In4.Cu" power)
		(12 "In5.Cu" mixed)
		(14 "In6.Cu" power)
		(16 "In7.Cu" mixed)
		(18 "In8.Cu" power)
		(2 "B.Cu" mixed)
		(9 "F.Adhes" user "F.Adhesive")
		(11 "B.Adhes" user "B.Adhesive")
		(13 "F.Paste" user)
		(15 "B.Paste" user)
		(5 "F.SilkS" user "F.Silkscreen")
		(7 "B.SilkS" user "B.Silkscreen")
		(1 "F.Mask" user)
		(3 "B.Mask" user)
		(17 "Dwgs.User" user "User.Drawings")
		(19 "Cmts.User" user "User.Comments")
		(21 "Eco1.User" user "User.Eco1")
		(23 "Eco2.User" user "User.Eco2")
		(25 "Edge.Cuts" user)
		(27 "Margin" user)
		(31 "F.CrtYd" user "F.Courtyard")
		(29 "B.CrtYd" user "B.Courtyard")
		(35 "F.Fab" user)
		(33 "B.Fab" user)
	)
	(footprint "antmicro-footprints:QFN-2L_1.6x1x0.55mm"
		(layer "B.Cu")
		(at 261.701 179.7)
		(property "Reference" "D3"
			(at -0.851 -0.7 0)
			(layer "B.SilkS")
			(effects
				(font
					(size 0.7 0.7)
					(thickness 0.15)
				)
				(justify right bottom mirror)
			)
		)
		(property "Value" "ESDA25P35-1U1M"
			(at 0 -1.7 0)
			(layer "B.Fab")
			(effects
				(font
					(size 0.7 0.7)
					(thickness 0.15)
				)
				(justify right bottom mirror)
			)
		)
		(property "Description" "Unidirectional TVS, 30 kV, QFN-2L, 22 V, 195 pF"
			(at 0 0 0)
			(layer "F.Fab")
			(hide yes)
			(effects
				(font
					(size 1.27 1.27)
					(thickness 0.15)
				)
			)
		)
		(property "Author" "Antmicro"
			(at 0 0 0)
			(layer "B.Fab")
			(hide yes)
			(effects
				(font
					(size 1 1)
					(thickness 0.15)
				)
				(justify mirror)
			)
		)
		(property "License" "Apache-2.0"
			(at 0 0 0)
			(layer "B.Fab")
			(hide yes)
			(effects
				(font
					(size 1 1)
					(thickness 0.15)
				)
				(justify mirror)
			)
		)
		(property "MPN" "ESDA25P35-1U1M"
			(at 0 0 0)
			(layer "B.Fab")
			(hide yes)
			(effects
				(font
					(size 1 1)
					(thickness 0.15)
				)
				(justify mirror)
			)
		)
		(property "Manufacturer" "STMicroelectronics"
			(at 0 0 0)
			(layer "B.Fab")
			(hide yes)
			(effects
				(font
					(size 1 1)
					(thickness 0.15)
				)
				(justify mirror)
			)
		)
		(property "Public" "False"
			(at 0 0 0)
			(layer "B.Fab")
			(hide yes)
			(effects
				(font
					(size 1 1)
					(thickness 0.15)
				)
				(justify mirror)
			)
		)
		(sheetname "Power supply")
		(sheetfile "power-supply.kicad_sch")
		(attr smd)
		(fp_line
			(start -1.2 0.4)
			(end -1.2 -0.4)
			(stroke
				(width 0.15)
				(type solid)
			)
			(layer "B.SilkS")
		)
		(fp_line
			(start 0.27 -0.3)
			(end -0.27 -0.3)
			(stroke
				(width 0.15)
				(type solid)
			)
			(layer "B.SilkS")
		)
		(fp_line
			(start 0.27 0.3)
			(end -0.27 0.3)
			(stroke
				(width 0.15)
				(type solid)
			)
			(layer "B.SilkS")
		)
		(fp_rect
			(start 1.25 -0.65)
			(end -1.25 0.65)
			(stroke
				(width 0.05)
				(type solid)
			)
			(fill no)
			(layer "B.CrtYd")
		)
		(fp_line
			(start -0.199 -0.2)
			(end -0.199 -0.1)
			(stroke
				(width 0.15)
				(type solid)
			)
			(layer "B.Fab")
		)
		(fp_line
			(start -0.199 0)
			(end -0.597 0)
			(stroke
				(width 0.15)
				(type solid)
			)
			(layer "B.Fab")
		)
		(fp_line
			(start -0.199 0.202)
			(end -0.199 -0.1)
			(stroke
				(width 0.15)
				(type solid)
			)
			(layer "B.Fab")
		)
		(fp_line
			(start -0.101 0)
			(end 0.201 -0.2)
			(stroke
				(width 0.15)
				(type solid)
			)
			(layer "B.Fab")
		)
		(fp_line
			(start 0.201 -0.2)
			(end 0.201 0)
			(stroke
				(width 0.15)
				(type solid)
			)
			(layer "B.Fab")
		)
		(fp_line
			(start 0.201 0)
			(end 0.201 0.202)
			(stroke
				(width 0.15)
				(type solid)
			)
			(layer "B.Fab")
		)
		(fp_line
			(start 0.201 0.202)
			(end -0.101 0)
			(stroke
				(width 0.15)
				(type solid)
			)
			(layer "B.Fab")
		)
		(fp_line
			(start 0.599 0)
			(end 0.201 0)
			(stroke
				(width 0.15)
				(type solid)
			)
			(layer "B.Fab")
		)
		(fp_rect
			(start 0.848 -0.4)
			(end -0.85 0.402)
			(stroke
				(width 0.15)
				(type solid)
			)
			(fill no)
			(layer "B.Fab")
		)
		(pad "1" smd roundrect
			(at -0.7 0 180)
			(size 0.8 1)
			(layers "B.Cu" "B.Mask" "B.Paste")
			(roundrect_rratio 0.2)
			(net 4 "/Power supply/DC_IN")
			(pinfunction "C")
			(pintype "passive")
		)
		(pad "2" smd roundrect
			(at 0.7 0 180)
			(size 0.8 1)
			(layers "B.Cu" "B.Mask" "B.Paste")
			(roundrect_rratio 0.2)
			(net 1 "GND")
			(pinfunction "A")
			(pintype "passive")
		)
	)
	(footprint "antmicro-footprints:C_0402_1005Metric"
		(layer "B.Cu")
		(at 191.5 144 90)
		(descr "Capacitor SMD 0402")
		(tags "capacitor SMD 0402")
		(property "Reference" "C91"
			(at 1.025 1.275 270)
			(layer "B.SilkS")
			(effects
				(font
					(size 0.7 0.7)
					(thickness 0.15)
				)
				(justify left bottom mirror)
			)
		)
		(property "Value" "C_100n_0402"
			(at 0 -1.169 270)
			(layer "B.Fab")
			(effects
				(font
					(size 0.7 0.7)
					(thickness 0.15)
				)
				(justify left bottom mirror)
			)
		)
		(property "Description" "SMD Multilayer Ceramic Capacitor, 0.1 µF, 50 V, 0402 [1005 Metric], ± 10%, X5R, GRM Series"
			(at 0 0 90)
			(layer "F.Fab")
			(hide yes)
			(effects
				(font
					(size 1.27 1.27)
					(thickness 0.15)
				)
			)
		)
		(property "Author" "Antmicro"
			(at 335.5 -47.5 0)
			(layer "B.Fab")
			(hide yes)
			(effects
				(font
					(size 1 1)
					(thickness 0.15)
				)
				(justify mirror)
			)
		)
		(property "Dielectric" "X5R"
			(at 335.5 -47.5 0)
			(layer "B.Fab")
			(hide yes)
			(effects
				(font
					(size 1 1)
					(thickness 0.15)
				)
				(justify mirror)
			)
		)
		(property "License" "Apache-2.0"
			(at 335.5 -47.5 0)
			(layer "B.Fab")
			(hide yes)
			(effects
				(font
					(size 1 1)
					(thickness 0.15)
				)
				(justify mirror)
			)
		)
		(property "MPN" "GRM155R61H104KE14D"
			(at 335.5 -47.5 0)
			(layer "B.Fab")
			(hide yes)
			(effects
				(font
					(size 1 1)
					(thickness 0.15)
				)
				(justify mirror)
			)
		)
		(property "Manufacturer" "Murata"
			(at 335.5 -47.5 0)
			(layer "B.Fab")
			(hide yes)
			(effects
				(font
					(size 1 1)
					(thickness 0.15)
				)
				(justify mirror)
			)
		)
		(property "Val" "100n"
			(at 335.5 -47.5 0)
			(layer "B.Fab")
			(hide yes)
			(effects
				(font
					(size 1 1)
					(thickness 0.15)
				)
				(justify mirror)
			)
		)
		(property "Voltage" "50V"
			(at 335.5 -47.5 0)
			(layer "B.Fab")
			(hide yes)
			(effects
				(font
					(size 1 1)
					(thickness 0.15)
				)
				(justify mirror)
			)
		)
		(sheetname "FPGA Bank 33 & 34")
		(sheetfile "fpga-bank-33-34.kicad_sch")
		(attr smd)
		(fp_rect
			(start -0.925 0.47)
			(end 0.925 -0.47)
			(stroke
				(width 0.05)
				(type default)
			)
			(fill no)
			(layer "B.CrtYd")
		)
		(fp_line
			(start 0.504 -0.248)
			(end -0.494 -0.248)
			(stroke
				(width 0.15)
				(type solid)
			)
			(layer "B.Fab")
		)
		(fp_line
			(start -0.494 -0.248)
			(end -0.494 0.25)
			(stroke
				(width 0.15)
				(type solid)
			)
			(layer "B.Fab")
		)
		(fp_line
			(start 0.504 0.25)
			(end 0.504 -0.248)
			(stroke
				(width 0.15)
				(type solid)
			)
			(layer "B.Fab")
		)
		(fp_line
			(start -0.494 0.25)
			(end 0.504 0.25)
			(stroke
				(width 0.15)
				(type solid)
			)
			(layer "B.Fab")
		)
		(pad "1" smd roundrect
			(at -0.48 0 90)
			(size 0.59 0.64)
			(layers "B.Cu" "B.Mask" "B.Paste")
			(roundrect_rratio 0.25)
			(net 1 "GND")
			(pintype "passive")
		)
		(pad "2" smd roundrect
			(at 0.48 0 90)
			(size 0.59 0.64)
			(layers "B.Cu" "B.Mask" "B.Paste")
			(roundrect_rratio 0.25)
			(net 25 "+1V35")
			(pintype "passive")
		)
	)
	(footprint "antmicro-footprints:C_0402_1005Metric"
		(layer "B.Cu")
		(at 201.75 119.05)
		(descr "Capacitor SMD 0402")
		(tags "capacitor SMD 0402")
		(property "Reference" "C87"
			(at 1.025 -0.475 180)
			(layer "B.SilkS")
			(effects
				(font
					(size 0.7 0.7)
					(thickness 0.15)
				)
				(justify left bottom mirror)
			)
		)
		(property "Value" "C_100n_0402"
			(at 0 -1.169 180)
			(layer "B.Fab")
			(effects
				(font
					(size 0.7 0.7)
					(thickness 0.15)
				)
				(justify left bottom mirror)
			)
		)
		(property "Description" "SMD Multilayer Ceramic Capacitor, 0.1 µF, 50 V, 0402 [1005 Metric], ± 10%, X5R, GRM Series"
			(at 0 0 0)
			(layer "F.Fab")
			(hide yes)
			(effects
				(font
					(size 1.27 1.27)
					(thickness 0.15)
				)
			)
		)
		(property "Author" "Antmicro"
			(at 0 0 0)
			(layer "B.Fab")
			(hide yes)
			(effects
				(font
					(size 1 1)
					(thickness 0.15)
				)
				(justify mirror)
			)
		)
		(property "Dielectric" "X5R"
			(at 0 0 0)
			(layer "B.Fab")
			(hide yes)
			(effects
				(font
					(size 1 1)
					(thickness 0.15)
				)
				(justify mirror)
			)
		)
		(property "License" "Apache-2.0"
			(at 0 0 0)
			(layer "B.Fab")
			(hide yes)
			(effects
				(font
					(size 1 1)
					(thickness 0.15)
				)
				(justify mirror)
			)
		)
		(property "MPN" "GRM155R61H104KE14D"
			(at 0 0 0)
			(layer "B.Fab")
			(hide yes)
			(effects
				(font
					(size 1 1)
					(thickness 0.15)
				)
				(justify mirror)
			)
		)
		(property "Manufacturer" "Murata"
			(at 0 0 0)
			(layer "B.Fab")
			(hide yes)
			(effects
				(font
					(size 1 1)
					(thickness 0.15)
				)
				(justify mirror)
			)
		)
		(property "Val" "100n"
			(at 0 0 0)
			(layer "B.Fab")
			(hide yes)
			(effects
				(font
					(size 1 1)
					(thickness 0.15)
				)
				(justify mirror)
			)
		)
		(property "Voltage" "50V"
			(at 0 0 0)
			(layer "B.Fab")
			(hide yes)
			(effects
				(font
					(size 1 1)
					(thickness 0.15)
				)
				(justify mirror)
			)
		)
		(sheetname "FPGA Bank 16 & 17")
		(sheetfile "fpga-bank-16-17.kicad_sch")
		(attr smd)
		(fp_rect
			(start -0.925 0.47)
			(end 0.925 -0.47)
			(stroke
				(width 0.05)
				(type default)
			)
			(fill no)
			(layer "B.CrtYd")
		)
		(fp_line
			(start -0.494 -0.248)
			(end -0.494 0.25)
			(stroke
				(width 0.15)
				(type solid)
			)
			(layer "B.Fab")
		)
		(fp_line
			(start -0.494 0.25)
			(end 0.504 0.25)
			(stroke
				(width 0.15)
				(type solid)
			)
			(layer "B.Fab")
		)
		(fp_line
			(start 0.504 -0.248)
			(end -0.494 -0.248)
			(stroke
				(width 0.15)
				(type solid)
			)
			(layer "B.Fab")
		)
		(fp_line
			(start 0.504 0.25)
			(end 0.504 -0.248)
			(stroke
				(width 0.15)
				(type solid)
			)
			(layer "B.Fab")
		)
		(pad "1" smd roundrect
			(at -0.48 0)
			(size 0.59 0.64)
			(layers "B.Cu" "B.Mask" "B.Paste")
			(roundrect_rratio 0.25)
			(net 1 "GND")
			(pintype "passive")
		)
		(pad "2" smd roundrect
			(at 0.48 0)
			(size 0.59 0.64)
			(layers "B.Cu" "B.Mask" "B.Paste")
			(roundrect_rratio 0.25)
			(net 24 "+3V3")
			(pintype "passive")
		)
	)
	(footprint "antmicro-footprints:R_0402_1005Metric"
		(layer "B.Cu")
		(at 266.001 124.7 180)
		(descr "Resistor SMD 0402")
		(tags "resistor SMD 0402")
		(property "Reference" "R169"
			(at 0.901 -0.7 0)
			(layer "B.SilkS")
			(effects
				(font
					(size 0.7 0.7)
					(thickness 0.15)
				)
				(justify left bottom mirror)
			)
		)
		(property "Value" "R_15k_0402"
			(at 0 -1.4 0)
			(layer "B.Fab")
			(effects
				(font
					(size 0.7 0.7)
					(thickness 0.15)
				)
				(justify left bottom mirror)
			)
		)
		(property "Description" "SMD Chip Resistor, 15 kohm, ± 1%, 62.5 mW, 0402 [1005 Metric], Thick Film, General Purpose"
			(at 0 0 180)
			(layer "F.Fab")
			(hide yes)
			(effects
				(font
					(size 1.27 1.27)
					(thickness 0.15)
				)
			)
		)
		(property "Author" "Antmicro"
			(at 532.002 249.4 0)
			(layer "B.Fab")
			(hide yes)
			(effects
				(font
					(size 1 1)
					(thickness 0.15)
				)
				(justify mirror)
			)
		)
		(property "DNP" "DNP"
			(at 532.002 249.4 0)
			(layer "B.Fab")
			(hide yes)
			(effects
				(font
					(size 1 1)
					(thickness 0.15)
				)
				(justify mirror)
			)
		)
		(property "License" "Apache-2.0"
			(at 532.002 249.4 0)
			(layer "B.Fab")
			(hide yes)
			(effects
				(font
					(size 1 1)
					(thickness 0.15)
				)
				(justify mirror)
			)
		)
		(property "MPN" "CR0402-FX-1502GLF"
			(at 532.002 249.4 0)
			(layer "B.Fab")
			(hide yes)
			(effects
				(font
					(size 1 1)
					(thickness 0.15)
				)
				(justify mirror)
			)
		)
		(property "Manufacturer" "Bourns"
			(at 532.002 249.4 0)
			(layer "B.Fab")
			(hide yes)
			(effects
				(font
					(size 1 1)
					(thickness 0.15)
				)
				(justify mirror)
			)
		)
		(property "Tolerance" "1%"
			(at 532.002 249.4 0)
			(layer "B.Fab")
			(hide yes)
			(effects
				(font
					(size 1 1)
					(thickness 0.15)
				)
				(justify mirror)
			)
		)
		(property "Val" "15k"
			(at 532.002 249.4 0)
			(layer "B.Fab")
			(hide yes)
			(effects
				(font
					(size 1 1)
					(thickness 0.15)
				)
				(justify mirror)
			)
		)
		(property "dnp" ""
			(at 532.002 249.4 0)
			(layer "B.Fab")
			(hide yes)
			(effects
				(font
					(size 1 1)
					(thickness 0.15)
				)
				(justify mirror)
			)
		)
		(property "exclude_from_bom" ""
			(at 532.002 249.4 0)
			(layer "B.Fab")
			(hide yes)
			(effects
				(font
					(size 1 1)
					(thickness 0.15)
				)
				(justify mirror)
			)
		)
		(sheetname "USB PHY")
		(sheetfile "usb-phy.kicad_sch")
		(attr smd exclude_from_bom)
		(fp_rect
			(start -0.925 0.47)
			(end 0.925 -0.47)
			(stroke
				(width 0.05)
				(type default)
			)
			(fill no)
			(layer "B.CrtYd")
		)
		(fp_rect
			(start -0.5 0.25)
			(end 0.5 -0.25)
			(stroke
				(width 0.15)
				(type solid)
			)
			(fill no)
			(layer "B.Fab")
		)
		(pad "1" smd roundrect
			(at -0.48 0 180)
			(size 0.59 0.64)
			(layers "B.Cu" "B.Mask" "B.Paste")
			(roundrect_rratio 0.25)
			(net 1 "GND")
			(pintype "passive")
		)
		(pad "2" smd roundrect
			(at 0.48 0 180)
			(size 0.59 0.64)
			(layers "B.Cu" "B.Mask" "B.Paste")
			(roundrect_rratio 0.25)
			(net 842 "/USB PHY/USB_USR_CONN_D+")
			(pintype "passive")
		)
	)
	(footprint "antmicro-footprints:C_0402_1005Metric"
		(layer "B.Cu")
		(at 192 122.275)
		(descr "Capacitor SMD 0402")
		(tags "capacitor SMD 0402")
		(property "Reference" "C111"
			(at 23.025 -29.55 180)
			(layer "B.SilkS")
			(effects
				(font
					(size 0.7 0.7)
					(thickness 0.15)
				)
				(justify left bottom mirror)
			)
		)
		(property "Value" "C_100n_0402"
			(at 0 -1.169 180)
			(layer "B.Fab")
			(effects
				(font
					(size 0.7 0.7)
					(thickness 0.15)
				)
				(justify left bottom mirror)
			)
		)
		(property "Description" "SMD Multilayer Ceramic Capacitor, 0.1 µF, 50 V, 0402 [1005 Metric], ± 10%, X5R, GRM Series"
			(at 0 0 0)
			(layer "F.Fab")
			(hide yes)
			(effects
				(font
					(size 1.27 1.27)
					(thickness 0.15)
				)
			)
		)
		(property "Author" "Antmicro"
			(at 0 0 0)
			(layer "B.Fab")
			(hide yes)
			(effects
				(font
					(size 1 1)
					(thickness 0.15)
				)
				(justify mirror)
			)
		)
		(property "Dielectric" "X5R"
			(at 0 0 0)
			(layer "B.Fab")
			(hide yes)
			(effects
				(font
					(size 1 1)
					(thickness 0.15)
				)
				(justify mirror)
			)
		)
		(property "License" "Apache-2.0"
			(at 0 0 0)
			(layer "B.Fab")
			(hide yes)
			(effects
				(font
					(size 1 1)
					(thickness 0.15)
				)
				(justify mirror)
			)
		)
		(property "MPN" "GRM155R61H104KE14D"
			(at 0 0 0)
			(layer "B.Fab")
			(hide yes)
			(effects
				(font
					(size 1 1)
					(thickness 0.15)
				)
				(justify mirror)
			)
		)
		(property "Manufacturer" "Murata"
			(at 0 0 0)
			(layer "B.Fab")
			(hide yes)
			(effects
				(font
					(size 1 1)
					(thickness 0.15)
				)
				(justify mirror)
			)
		)
		(property "Val" "100n"
			(at 0 0 0)
			(layer "B.Fab")
			(hide yes)
			(effects
				(font
					(size 1 1)
					(thickness 0.15)
				)
				(justify mirror)
			)
		)
		(property "Voltage" "50V"
			(at 0 0 0)
			(layer "B.Fab")
			(hide yes)
			(effects
				(font
					(size 1 1)
					(thickness 0.15)
				)
				(justify mirror)
			)
		)
		(sheetname "FPGA supply")
		(sheetfile "fpga-supply.kicad_sch")
		(attr smd)
		(fp_rect
			(start -0.925 0.47)
			(end 0.925 -0.47)
			(stroke
				(width 0.05)
				(type default)
			)
			(fill no)
			(layer "B.CrtYd")
		)
		(fp_line
			(start -0.494 -0.248)
			(end -0.494 0.25)
			(stroke
				(width 0.15)
				(type solid)
			)
			(layer "B.Fab")
		)
		(fp_line
			(start -0.494 0.25)
			(end 0.504 0.25)
			(stroke
				(width 0.15)
				(type solid)
			)
			(layer "B.Fab")
		)
		(fp_line
			(start 0.504 -0.248)
			(end -0.494 -0.248)
			(stroke
				(width 0.15)
				(type solid)
			)
			(layer "B.Fab")
		)
		(fp_line
			(start 0.504 0.25)
			(end 0.504 -0.248)
			(stroke
				(width 0.15)
				(type solid)
			)
			(layer "B.Fab")
		)
		(pad "1" smd roundrect
			(at -0.48 0)
			(size 0.59 0.64)
			(layers "B.Cu" "B.Mask" "B.Paste")
			(roundrect_rratio 0.25)
			(net 6 "+1V0_MGTAVCC")
			(pintype "passive")
		)
		(pad "2" smd roundrect
			(at 0.48 0)
			(size 0.59 0.64)
			(layers "B.Cu" "B.Mask" "B.Paste")
			(roundrect_rratio 0.25)
			(net 1 "GND")
			(pintype "passive")
		)
	)
	(footprint "antmicro-footprints:C_0201"
		(layer "B.Cu")
		(at 202.65 126.5 -90)
		(descr "Capacitor SMD 0201")
		(tags "capacitor SMD 0201")
		(property "Reference" "C129"
			(at -31.25 -27 90)
			(layer "B.SilkS")
			(effects
				(font
					(size 0.7 0.7)
					(thickness 0.15)
				)
				(justify left bottom mirror)
			)
		)
		(property "Value" "C_100n_0201"
			(at 0 -1.4 90)
			(layer "B.Fab")
			(effects
				(font
					(size 0.7 0.7)
					(thickness 0.15)
				)
				(justify left bottom mirror)
			)
		)
		(property "Description" "SMD Multilayer Ceramic Capacitor, 0.1 µF, 6.3 V, 0201 [0603 Metric], ± 10%, X6S, CC Series"
			(at 0 0 270)
			(layer "F.Fab")
			(hide yes)
			(effects
				(font
					(size 1.27 1.27)
					(thickness 0.15)
				)
			)
		)
		(property "Author" "Antmicro"
			(at 76.15 329.15 0)
			(layer "B.Fab")
			(hide yes)
			(effects
				(font
					(size 1 1)
					(thickness 0.15)
				)
				(justify mirror)
			)
		)
		(property "Dielectric" ""
			(at 76.15 329.15 0)
			(layer "B.Fab")
			(hide yes)
			(effects
				(font
					(size 1 1)
					(thickness 0.15)
				)
				(justify mirror)
			)
		)
		(property "License" "Apache-2.0"
			(at 76.15 329.15 0)
			(layer "B.Fab")
			(hide yes)
			(effects
				(font
					(size 1 1)
					(thickness 0.15)
				)
				(justify mirror)
			)
		)
		(property "MPN" "CC0201KRX6S5BB104"
			(at 76.15 329.15 0)
			(layer "B.Fab")
			(hide yes)
			(effects
				(font
					(size 1 1)
					(thickness 0.15)
				)
				(justify mirror)
			)
		)
		(property "Manufacturer" "YAGEO"
			(at 76.15 329.15 0)
			(layer "B.Fab")
			(hide yes)
			(effects
				(font
					(size 1 1)
					(thickness 0.15)
				)
				(justify mirror)
			)
		)
		(property "Val" "100n"
			(at 76.15 329.15 0)
			(layer "B.Fab")
			(hide yes)
			(effects
				(font
					(size 1 1)
					(thickness 0.15)
				)
				(justify mirror)
			)
		)
		(property "Voltage" ""
			(at 76.15 329.15 0)
			(layer "B.Fab")
			(hide yes)
			(effects
				(font
					(size 1 1)
					(thickness 0.15)
				)
				(justify mirror)
			)
		)
		(sheetname "FPGA supply")
		(sheetfile "fpga-supply.kicad_sch")
		(attr smd)
		(fp_rect
			(start -0.7 0.35)
			(end 0.7 -0.35)
			(stroke
				(width 0.05)
				(type default)
			)
			(fill no)
			(layer "B.CrtYd")
		)
		(fp_rect
			(start 0.3 -0.15)
			(end -0.301 0.149)
			(stroke
				(width 0.15)
				(type solid)
			)
			(fill no)
			(layer "B.Fab")
		)
		(pad "" smd roundrect
			(at -0.349 0.002 270)
			(size 0.318 0.36)
			(layers "B.Paste")
			(roundrect_rratio 0.25)
		)
		(pad "" smd roundrect
			(at 0.341 0.002 270)
			(size 0.318 0.36)
			(layers "B.Paste")
			(roundrect_rratio 0.25)
		)
		(pad "1" smd roundrect
			(at -0.321 0.002 270)
			(size 0.46 0.4)
			(layers "B.Cu" "B.Mask")
			(roundrect_rratio 0.25)
			(net 1 "GND")
			(pintype "passive")
		)
		(pad "2" smd roundrect
			(at 0.32 0.002 270)
			(size 0.46 0.4)
			(layers "B.Cu" "B.Mask")
			(roundrect_rratio 0.25)
			(net 650 "+1V0")
			(pintype "passive")
		)
	)
)
